(kicad_pcb
	(version 20241229)
	(generator "pcbnew")
	(generator_version "9.0")
	(general
		(thickness 1.62)
		(legacy_teardrops no)
	)
	(paper "A3")
	(title_block
		(title "COM Express 7 Baseboard")
		(date "2025-02-04")
		(rev "1.1.2")
		(company "Antmicro Ltd")
		(comment 1 "www.antmicro.com")
		(comment 9 "footprints 69-73 of 802")
	)
	(layers
		(0 "F.Cu" signal)
		(4 "In1.Cu" signal)
		(6 "In2.Cu" signal)
		(8 "In3.Cu" signal)
		(10 "In4.Cu" signal)
		(12 "In5.Cu" signal)
		(14 "In6.Cu" signal)
		(2 "B.Cu" signal)
		(9 "F.Adhes" user "F.Adhesive")
		(11 "B.Adhes" user "B.Adhesive")
		(13 "F.Paste" user)
		(15 "B.Paste" user)
		(5 "F.SilkS" user "F.Silkscreen")
		(7 "B.SilkS" user "B.Silkscreen")
		(1 "F.Mask" user)
		(3 "B.Mask" user)
		(17 "Dwgs.User" user "User.Drawings")
		(19 "Cmts.User" user "User.Comments")
		(21 "Eco1.User" user "User.Eco1")
		(23 "Eco2.User" user "User.Eco2")
		(25 "Edge.Cuts" user)
		(27 "Margin" user)
		(31 "F.CrtYd" user "F.Courtyard")
		(29 "B.CrtYd" user "B.Courtyard")
		(35 "F.Fab" user)
		(33 "B.Fab" user)
	)
	(footprint "antmicro-footprints:TP_SMD_0.75mm"
		(layer "F.Cu")
		(at 148.55 129.56)
		(property "Reference" "TP68"
			(at 0.45 -1.25 90)
			(layer "F.SilkS")
			(effects
				(font
					(size 0.7 0.7)
					(thickness 0.15)
				)
				(justify left bottom)
			)
		)
		(property "Value" "TP_0.75mm_SMD"
			(at 0 1.2 0)
			(layer "F.Fab")
			(effects
				(font
					(size 0.7 0.7)
					(thickness 0.15)
				)
				(justify left bottom)
			)
		)
		(property "Author" "Antmicro"
			(at 0 0 0)
			(layer "F.Fab")
			(hide yes)
			(effects
				(font
					(size 1 1)
					(thickness 0.15)
				)
			)
		)
		(property "License" "Apache-2.0"
			(at 0 0 0)
			(layer "F.Fab")
			(hide yes)
			(effects
				(font
					(size 1 1)
					(thickness 0.15)
				)
			)
		)
		(property "MPN" ""
			(at 0 0 0)
			(layer "F.Fab")
			(hide yes)
			(effects
				(font
					(size 1 1)
					(thickness 0.15)
				)
			)
		)
		(property "Manufacturer" ""
			(at 0 0 0)
			(layer "F.Fab")
			(hide yes)
			(effects
				(font
					(size 1 1)
					(thickness 0.15)
				)
			)
		)
		(property "Public" "False"
			(at 0 0 0)
			(layer "F.Fab")
			(hide yes)
			(effects
				(font
					(size 1 1)
					(thickness 0.15)
				)
			)
		)
		(sheetname "KR to SFI #1")
		(sheetfile "kr_sfi.kicad_sch")
		(attr exclude_from_pos_files exclude_from_bom)
		(fp_circle
			(center 0 0)
			(end 0.475 0)
			(stroke
				(width 0.05)
				(type default)
			)
			(fill no)
			(layer "F.CrtYd")
		)
		(pad "1" smd circle
			(at 0 0)
			(size 0.75 0.75)
			(layers "F.Cu" "F.Mask")
			(net 731 "Net-(U43C-CLKOUTA-)")
			(pinfunction "1")
			(pintype "passive")
			(teardrops
				(best_length_ratio 0.4)
				(max_length 1)
				(best_width_ratio 0.9)
				(max_width 2)
				(curved_edges yes)
				(filter_ratio 0.9)
				(enabled yes)
				(allow_two_segments yes)
				(prefer_zone_connections yes)
			)
		)
	)
	(footprint "antmicro-footprints:Trans_Eth_4.7x3.3mm"
		(layer "F.Cu")
		(at 130.63 100.46)
		(property "Reference" "T8"
			(at 4.92 0.25 0)
			(unlocked yes)
			(layer "F.SilkS")
			(effects
				(font
					(size 0.7 0.7)
					(thickness 0.15)
				)
				(justify left bottom)
			)
		)
		(property "Value" "Trans_SM453229-381N7Y"
			(at 2.39 11.52 0)
			(unlocked yes)
			(layer "F.Fab")
			(effects
				(font
					(size 0.7 0.7)
					(thickness 0.15)
				)
				(justify left bottom)
			)
		)
		(property "Datasheet" "https://eu.mouser.com/datasheet/2/54/bourns_02132019_SM453229-381N7Y_datasheet-1532071.pdf"
			(at 0 0 0)
			(layer "F.Fab")
			(hide yes)
			(effects
				(font
					(size 1.27 1.27)
					(thickness 0.15)
				)
			)
		)
		(property "Author" "Antmicro"
			(at 0 0 0)
			(layer "F.Fab")
			(hide yes)
			(effects
				(font
					(size 1 1)
					(thickness 0.15)
				)
			)
		)
		(property "License" "Apache-2.0"
			(at 0 0 0)
			(layer "F.Fab")
			(hide yes)
			(effects
				(font
					(size 1 1)
					(thickness 0.15)
				)
			)
		)
		(property "MPN" "SM453229-381N7Y"
			(at 0 0 0)
			(layer "F.Fab")
			(hide yes)
			(effects
				(font
					(size 1 1)
					(thickness 0.15)
				)
			)
		)
		(property "Manufacturer" "Bourns"
			(at 0 0 0)
			(layer "F.Fab")
			(hide yes)
			(effects
				(font
					(size 1 1)
					(thickness 0.15)
				)
			)
		)
		(sheetname "2xUSB3.0+RJ45")
		(sheetfile "usb3+rj45.kicad_sch")
		(attr smd)
		(fp_line
			(start -0.15 -0.6)
			(end -0.15 0.55)
			(stroke
				(width 0.1)
				(type default)
			)
			(layer "F.SilkS")
		)
		(fp_line
			(start 3.4 -1.6)
			(end 1 -1.6)
			(stroke
				(width 0.1)
				(type default)
			)
			(layer "F.SilkS")
		)
		(fp_line
			(start 3.4 1.7)
			(end 1 1.7)
			(stroke
				(width 0.1)
				(type default)
			)
			(layer "F.SilkS")
		)
		(fp_line
			(start 4.55 -0.25)
			(end 4.55 0.9)
			(stroke
				(width 0.1)
				(type default)
			)
			(layer "F.SilkS")
		)
		(fp_circle
			(center 0.1 2.3)
			(end 0.15 2.3)
			(stroke
				(width 0.15)
				(type solid)
			)
			(fill yes)
			(layer "F.SilkS")
		)
		(fp_rect
			(start -0.6 -1.9)
			(end 4.94 1.9)
			(stroke
				(width 0.05)
				(type solid)
			)
			(fill no)
			(layer "F.CrtYd")
		)
		(pad "1" smd roundrect
			(at 0.17 1.5)
			(size 0.96 0.27)
			(layers "F.Cu" "F.Mask" "F.Paste")
			(roundrect_rratio 0.25)
			(net 695 "/2xUSB3.0+RJ45/DD_FL+")
			(pinfunction "1")
			(pintype "passive")
			(teardrops
				(best_length_ratio 0.2)
				(max_length 1)
				(best_width_ratio 0.9)
				(max_width 2)
				(curved_edges yes)
				(filter_ratio 0.9)
				(enabled yes)
				(allow_two_segments yes)
				(prefer_zone_connections yes)
			)
		)
		(pad "2" smd roundrect
			(at 0.115 0.855)
			(size 0.85 0.28)
			(layers "F.Cu" "F.Mask" "F.Paste")
			(roundrect_rratio 0.25)
			(net 696 "/2xUSB3.0+RJ45/DD_FL-")
			(pinfunction "2")
			(pintype "passive")
			(teardrops
				(best_length_ratio 0.2)
				(max_length 1)
				(best_width_ratio 0.9)
				(max_width 2)
				(curved_edges yes)
				(filter_ratio 0.9)
				(enabled yes)
				(allow_two_segments yes)
				(prefer_zone_connections yes)
			)
		)
		(pad "3" smd roundrect
			(at 0.14 -1.21)
			(size 0.9 0.77)
			(layers "F.Cu" "F.Mask" "F.Paste")
			(roundrect_rratio 0.1)
			(net 51 "Net-(C13-Pad1)")
			(pinfunction "3")
			(pintype "passive")
			(teardrops
				(best_length_ratio 0.2)
				(max_length 1)
				(best_width_ratio 0.9)
				(max_width 2)
				(curved_edges yes)
				(filter_ratio 0.9)
				(enabled yes)
				(allow_two_segments yes)
				(prefer_zone_connections yes)
			)
		)
		(pad "5" smd roundrect
			(at 4.215 1.385)
			(size 0.95 0.5)
			(layers "F.Cu" "F.Mask" "F.Paste")
			(roundrect_rratio 0.1)
			(net 552 "Net-(R17-Pad2)")
			(pinfunction "5")
			(pintype "passive")
			(teardrops
				(best_length_ratio 0.2)
				(max_length 1)
				(best_width_ratio 0.9)
				(max_width 2)
				(curved_edges yes)
				(filter_ratio 0.9)
				(enabled yes)
				(allow_two_segments yes)
				(prefer_zone_connections yes)
			)
		)
		(pad "6" smd roundrect
			(at 4.265 -0.645)
			(size 0.85 0.34)
			(layers "F.Cu" "F.Mask" "F.Paste")
			(roundrect_rratio 0.1)
			(net 286 "/2xUSB3.0+RJ45/GbE.MDI3+")
			(pinfunction "6")
			(pintype "passive")
			(teardrops
				(best_length_ratio 0.2)
				(max_length 1)
				(best_width_ratio 0.9)
				(max_width 2)
				(curved_edges yes)
				(filter_ratio 0.9)
				(enabled yes)
				(allow_two_segments yes)
				(prefer_zone_connections yes)
			)
		)
		(pad "7" smd roundrect
			(at 4.205 -1.43)
			(size 0.97 0.33)
			(layers "F.Cu" "F.Mask" "F.Paste")
			(roundrect_rratio 0.1)
			(net 285 "/2xUSB3.0+RJ45/GbE.MDI3-")
			(pinfunction "7")
			(pintype "passive")
			(teardrops
				(best_length_ratio 0.2)
				(max_length 1)
				(best_width_ratio 0.9)
				(max_width 2)
				(curved_edges yes)
				(filter_ratio 0.9)
				(enabled yes)
				(allow_two_segments yes)
				(prefer_zone_connections yes)
			)
		)
	)
	(footprint "antmicro-footprints:R_0402_1005Metric"
		(layer "F.Cu")
		(at 111.206999 75.326)
		(descr "Resistor SMD 0402")
		(tags "resistor SMD 0402")
		(property "Reference" "R69"
			(at -1.106999 -0.466 0)
			(layer "F.SilkS")
			(effects
				(font
					(size 0.7 0.7)
					(thickness 0.15)
				)
				(justify left bottom)
			)
		)
		(property "Value" "R_27R_0402"
			(at -1.011843 1.772047 0)
			(layer "F.Fab")
			(effects
				(font
					(size 0.7 0.7)
					(thickness 0.15)
				)
				(justify left bottom)
			)
		)
		(property "Datasheet" "https://www.bourns.com/docs/product-datasheets/cr.pdf"
			(at 0 0 0)
			(layer "F.Fab")
			(hide yes)
			(effects
				(font
					(size 1.27 1.27)
					(thickness 0.15)
				)
			)
		)
		(property "Author" "Antmicro"
			(at 0 0 0)
			(layer "F.Fab")
			(hide yes)
			(effects
				(font
					(size 1 1)
					(thickness 0.15)
				)
			)
		)
		(property "License" "Apache-2.0"
			(at 0 0 0)
			(layer "F.Fab")
			(hide yes)
			(effects
				(font
					(size 1 1)
					(thickness 0.15)
				)
			)
		)
		(property "MPN" "CR0402-FX-27R0GLF"
			(at 0 0 0)
			(layer "F.Fab")
			(hide yes)
			(effects
				(font
					(size 1 1)
					(thickness 0.15)
				)
			)
		)
		(property "Manufacturer" "Bourns"
			(at 0 0 0)
			(layer "F.Fab")
			(hide yes)
			(effects
				(font
					(size 1 1)
					(thickness 0.15)
				)
			)
		)
		(property "Public" "False"
			(at 0 0 0)
			(layer "F.Fab")
			(hide yes)
			(effects
				(font
					(size 1 1)
					(thickness 0.15)
				)
			)
		)
		(property "Tolerance" "1%"
			(at 0 0 0)
			(layer "F.Fab")
			(hide yes)
			(effects
				(font
					(size 1 1)
					(thickness 0.15)
				)
			)
		)
		(property "Val" "27R"
			(at 0 0 0)
			(layer "F.Fab")
			(hide yes)
			(effects
				(font
					(size 1 1)
					(thickness 0.15)
				)
			)
		)
		(sheetname "USB-C console")
		(sheetfile "usb-c_console.kicad_sch")
		(attr smd)
		(fp_rect
			(start -0.925 -0.47)
			(end 0.925 0.47)
			(stroke
				(width 0.05)
				(type default)
			)
			(fill no)
			(layer "F.CrtYd")
		)
		(fp_rect
			(start -0.5 -0.25)
			(end 0.5 0.25)
			(stroke
				(width 0.15)
				(type solid)
			)
			(fill no)
			(layer "F.Fab")
		)
		(pad "1" smd roundrect
			(at -0.48 0)
			(size 0.59 0.64)
			(layers "F.Cu" "F.Mask" "F.Paste")
			(roundrect_rratio 0.25)
			(net 55 "/USB-C console/USB_D+")
			(pintype "passive")
			(teardrops
				(best_length_ratio 0.2)
				(max_length 1)
				(best_width_ratio 0.9)
				(max_width 2)
				(curved_edges yes)
				(filter_ratio 0.9)
				(enabled yes)
				(allow_two_segments yes)
				(prefer_zone_connections yes)
			)
		)
		(pad "2" smd roundrect
			(at 0.48 0)
			(size 0.59 0.64)
			(layers "F.Cu" "F.Mask" "F.Paste")
			(roundrect_rratio 0.25)
			(net 568 "/USB-C console/FTDI_D+")
			(pintype "passive")
			(teardrops
				(best_length_ratio 0.2)
				(max_length 1)
				(best_width_ratio 0.9)
				(max_width 2)
				(curved_edges yes)
				(filter_ratio 0.9)
				(enabled yes)
				(allow_two_segments yes)
				(prefer_zone_connections yes)
			)
		)
	)
	(footprint "antmicro-footprints:Oscillator_SMD_Epson_SG3225EEN_3.2x2.5x1.2mm"
		(layer "F.Cu")
		(at 123.79 138.01 -90)
		(property "Reference" "Y3"
			(at 2.45 -0.46 0)
			(unlocked yes)
			(layer "F.SilkS")
			(effects
				(font
					(size 0.7 0.7)
					(thickness 0.15)
				)
				(justify left bottom)
			)
		)
		(property "Value" "Oscillator_156.25MHz_SG3225EEN"
			(at 0 3 270)
			(unlocked yes)
			(layer "F.Fab")
			(effects
				(font
					(size 0.7 0.7)
					(thickness 0.15)
				)
				(justify left bottom)
			)
		)
		(property "Datasheet" "https://support.epson.biz/td/api/doc_check.php?dl=brief_SG3225EEN&lang=en"
			(at 0 0 270)
			(layer "F.Fab")
			(hide yes)
			(effects
				(font
					(size 1.27 1.27)
					(thickness 0.15)
				)
			)
		)
		(property "Author" "Antmicro"
			(at -14.22 261.8 0)
			(layer "F.Fab")
			(hide yes)
			(effects
				(font
					(size 1 1)
					(thickness 0.15)
				)
			)
		)
		(property "License" "Apache-2.0"
			(at -14.22 261.8 0)
			(layer "F.Fab")
			(hide yes)
			(effects
				(font
					(size 1 1)
					(thickness 0.15)
				)
			)
		)
		(property "MPN" "SG3225EEN_156.250000M-CDGA3"
			(at -14.22 261.8 0)
			(layer "F.Fab")
			(hide yes)
			(effects
				(font
					(size 1 1)
					(thickness 0.15)
				)
			)
		)
		(property "Manufacturer" "Epson"
			(at -14.22 261.8 0)
			(layer "F.Fab")
			(hide yes)
			(effects
				(font
					(size 1 1)
					(thickness 0.15)
				)
			)
		)
		(property "Public" "False"
			(at -14.22 261.8 0)
			(layer "F.Fab")
			(hide yes)
			(effects
				(font
					(size 1 1)
					(thickness 0.15)
				)
			)
		)
		(property "Val" "156.25MHz"
			(at -14.22 261.8 0)
			(layer "F.Fab")
			(hide yes)
			(effects
				(font
					(size 1 1)
					(thickness 0.15)
				)
			)
		)
		(sheetname "KR to SFI #2")
		(sheetfile "kr_sfi.kicad_sch")
		(attr smd)
		(fp_line
			(start 1.25 1.925)
			(end -1.25 1.925)
			(stroke
				(width 0.15)
				(type solid)
			)
			(layer "F.SilkS")
		)
		(fp_line
			(start 1.25 -1.825)
			(end -1.25 -1.825)
			(stroke
				(width 0.15)
				(type solid)
			)
			(layer "F.SilkS")
		)
		(fp_circle
			(center -1.57 -1.87)
			(end -1.57 -1.82)
			(stroke
				(width 0.15)
				(type solid)
			)
			(fill yes)
			(layer "F.SilkS")
		)
		(fp_rect
			(start 1.58 -1.85)
			(end -1.6 1.96)
			(stroke
				(width 0.05)
				(type solid)
			)
			(fill no)
			(layer "F.CrtYd")
		)
		(pad "1" smd rect
			(at -0.925 -1.24 180)
			(size 0.92 1.05)
			(layers "F.Cu" "F.Mask" "F.Paste")
			(net 668 "Net-(Y3-EN)")
			(pinfunction "EN")
			(pintype "input")
			(solder_mask_margin 0.05)
			(teardrops
				(best_length_ratio 0.2)
				(max_length 1)
				(best_width_ratio 0.9)
				(max_width 2)
				(curved_edges yes)
				(filter_ratio 0.9)
				(enabled yes)
				(allow_two_segments yes)
				(prefer_zone_connections yes)
			)
		)
		(pad "2" smd rect
			(at -0.925 0.05 180)
			(size 0.8 1.05)
			(layers "F.Cu" "F.Mask" "F.Paste")
			(net 865 "unconnected-(Y3-NC-Pad2)")
			(pinfunction "NC")
			(pintype "no_connect")
			(solder_mask_margin 0.05)
			(teardrops
				(best_length_ratio 0.2)
				(max_length 1)
				(best_width_ratio 0.9)
				(max_width 2)
				(curved_edges yes)
				(filter_ratio 0.9)
				(enabled yes)
				(allow_two_segments yes)
				(prefer_zone_connections yes)
			)
		)
		(pad "3" smd rect
			(at -0.925 1.34 180)
			(size 0.92 1.05)
			(layers "F.Cu" "F.Mask" "F.Paste")
			(net 1 "GND")
			(pinfunction "GND")
			(pintype "power_in")
			(solder_mask_margin 0.05)
			(teardrops
				(best_length_ratio 0.2)
				(max_length 1)
				(best_width_ratio 0.9)
				(max_width 2)
				(curved_edges yes)
				(filter_ratio 0.9)
				(enabled yes)
				(allow_two_segments yes)
				(prefer_zone_connections yes)
			)
		)
		(pad "4" smd rect
			(at 0.925 1.34 180)
			(size 0.92 1.05)
			(layers "F.Cu" "F.Mask" "F.Paste")
			(net 115 "/2xSFP+/KR to SFI #2/CLK+")
			(pinfunction "OUT+")
			(pintype "output")
			(solder_mask_margin 0.05)
			(teardrops
				(best_length_ratio 0.2)
				(max_length 1)
				(best_width_ratio 0.9)
				(max_width 2)
				(curved_edges yes)
				(filter_ratio 0.9)
				(enabled yes)
				(allow_two_segments yes)
				(prefer_zone_connections yes)
			)
		)
		(pad "5" smd rect
			(at 0.925 0.05 180)
			(size 0.8 1.05)
			(layers "F.Cu" "F.Mask" "F.Paste")
			(net 117 "/2xSFP+/KR to SFI #2/CLK-")
			(pinfunction "OUT-")
			(pintype "output")
			(solder_mask_margin 0.05)
			(teardrops
				(best_length_ratio 0.2)
				(max_length 1)
				(best_width_ratio 0.9)
				(max_width 2)
				(curved_edges yes)
				(filter_ratio 0.9)
				(enabled yes)
				(allow_two_segments yes)
				(prefer_zone_connections yes)
			)
		)
		(pad "6" smd rect
			(at 0.925 -1.24 180)
			(size 0.92 1.05)
			(layers "F.Cu" "F.Mask" "F.Paste")
			(net 2 "+3V3")
			(pinfunction "VCC")
			(pintype "power_in")
			(solder_mask_margin 0.05)
			(teardrops
				(best_length_ratio 0.2)
				(max_length 1)
				(best_width_ratio 0.9)
				(max_width 2)
				(curved_edges yes)
				(filter_ratio 0.9)
				(enabled yes)
				(allow_two_segments yes)
				(prefer_zone_connections yes)
			)
		)
	)
	(footprint "antmicro-footprints:TP_SMD_0.75mm"
		(layer "F.Cu")
		(at 126.49 129.56)
		(property "Reference" "TP78"
			(at 0.46 -1.25 90)
			(layer "F.SilkS")
			(effects
				(font
					(size 0.7 0.7)
					(thickness 0.15)
				)
				(justify left bottom)
			)
		)
		(property "Value" "TP_0.75mm_SMD"
			(at 0 1.2 0)
			(layer "F.Fab")
			(effects
				(font
					(size 0.7 0.7)
					(thickness 0.15)
				)
				(justify left bottom)
			)
		)
		(property "Author" "Antmicro"
			(at 0 0 0)
			(layer "F.Fab")
			(hide yes)
			(effects
				(font
					(size 1 1)
					(thickness 0.15)
				)
			)
		)
		(property "License" "Apache-2.0"
			(at 0 0 0)
			(layer "F.Fab")
			(hide yes)
			(effects
				(font
					(size 1 1)
					(thickness 0.15)
				)
			)
		)
		(property "MPN" ""
			(at 0 0 0)
			(layer "F.Fab")
			(hide yes)
			(effects
				(font
					(size 1 1)
					(thickness 0.15)
				)
			)
		)
		(property "Manufacturer" ""
			(at 0 0 0)
			(layer "F.Fab")
			(hide yes)
			(effects
				(font
					(size 1 1)
					(thickness 0.15)
				)
			)
		)
		(property "Public" "False"
			(at 0 0 0)
			(layer "F.Fab")
			(hide yes)
			(effects
				(font
					(size 1 1)
					(thickness 0.15)
				)
			)
		)
		(sheetname "KR to SFI #2")
		(sheetfile "kr_sfi.kicad_sch")
		(attr exclude_from_pos_files exclude_from_bom)
		(fp_circle
			(center 0 0)
			(end 0.475 0)
			(stroke
				(width 0.05)
				(type default)
			)
			(fill no)
			(layer "F.CrtYd")
		)
		(pad "1" smd circle
			(at 0 0)
			(size 0.75 0.75)
			(layers "F.Cu" "F.Mask")
			(net 741 "Net-(U45C-REFCLK1-)")
			(pinfunction "1")
			(pintype "passive")
			(teardrops
				(best_length_ratio 0.4)
				(max_length 1)
				(best_width_ratio 0.9)
				(max_width 2)
				(curved_edges yes)
				(filter_ratio 0.9)
				(enabled yes)
				(allow_two_segments yes)
				(prefer_zone_connections yes)
			)
		)
	)
)
